# S9S_MB_2U (Grand Teton) — schematic netlist excerpt (pin names and nets, part order shuffled) for the footprints in the layout excerpt that follows; sources: Cadence DE-HDL packaged netlist, KiCad conversion of 03242023_DA0F0TMBIJ0_F0T_Motherboard_J_brd_V01_OCP.brd

PC2193  Q_CAP  0.047UF 25V 10% X7R  pkg C0402  page 301 : A = HSC_IMON ; B = AGND_HSC
PC190_P0_2  Q_CAP  3300PF 50V 10% X7R  pkg 0402  page 275 : A = SW_P12V_PVCCINFAON_CPU0_FLT ; B = GND

(kicad_pcb
	(version 20260206)
	(generator "pcbnew")
	(generator_version "10.0")
	(general
		(thickness 1.6)
		(legacy_teardrops no)
	)
	(paper "A4")
	(title_block
		(title "03242023_DA0F0TMBIJ0_F0T_Motherboard_J_brd_V01_OCP.brd")
		(comment 1 "Grand Teton / footprints 821-822 of 6105")
	)
	(layers
		(0 "F.Cu" signal "TOP")
		(4 "In1.Cu" signal "GND")
		(6 "In2.Cu" signal "IN1")
		(8 "In3.Cu" signal "GND1")
		(10 "In4.Cu" signal "IN2")
		(12 "In5.Cu" signal "GND2")
		(14 "In6.Cu" signal "IN3")
		(16 "In7.Cu" signal "GND3")
		(18 "In8.Cu" signal "VCC")
		(20 "In9.Cu" signal "VCC1")
		(22 "In10.Cu" signal "GND4")
		(24 "In11.Cu" signal "IN4")
		(26 "In12.Cu" signal "GND5")
		(28 "In13.Cu" signal "IN5")
		(30 "In14.Cu" signal "GND6")
		(32 "In15.Cu" signal "IN6")
		(34 "In16.Cu" signal "GND7")
		(2 "B.Cu" signal "BOTTOM")
		(9 "F.Adhes" user "F.Adhesive")
		(11 "B.Adhes" user "B.Adhesive")
		(13 "F.Paste" user "Package Geometry/Pastemask Top")
		(15 "B.Paste" user "Package Geometry/Pastemask Bottom")
		(5 "F.SilkS" user "Ref Des/Silkscreen Top")
		(7 "B.SilkS" user "Ref Des/Silkscreen Bottom")
		(1 "F.Mask" user "Board Geometry/Soldermask Top")
		(3 "B.Mask" user "Board Geometry/Soldermask Bottom")
		(17 "Dwgs.User" user "User.Drawings")
		(19 "Cmts.User" user "User.Comments")
		(21 "Eco1.User" user "User.Eco1")
		(23 "Eco2.User" user "User.Eco2")
		(25 "Edge.Cuts" user "Board Geometry/Outline")
		(27 "Margin" user)
		(31 "F.CrtYd" user "Package Geometry/Place Bound Top")
		(29 "B.CrtYd" user "Package Geometry/Place Bound Bottom")
		(35 "F.Fab" user "Ref Des/Assembly Top")
		(33 "B.Fab" user "Ref Des/Assembly Bottom")
	)
	(footprint ""
		(layer "F.Cu")
		(at 179.352448 -398.191482 180)
		(property "Reference" "PC2193"
			(at 0 0 180)
			(layer "F.SilkS")
			(hide yes)
			(effects
				(font
					(size 1.27 1.27)
				)
			)
		)
		(property "Value" ""
			(at 0 0 180)
			(layer "F.Fab")
			(effects
				(font
					(size 1.27 1.27)
				)
			)
		)
		(duplicate_pad_numbers_are_jumpers no)
		(fp_line
			(start 0.7874 0.4064)
			(end -0.7874 0.4064)
			(stroke
				(width 0.1524)
				(type default)
			)
			(layer "F.SilkS")
		)
		(fp_line
			(start 0.7874 -0.4064)
			(end 0.7874 0.4064)
			(stroke
				(width 0.1524)
				(type default)
			)
			(layer "F.SilkS")
		)
		(fp_line
			(start -0.7874 0.4064)
			(end -0.7874 -0.4064)
			(stroke
				(width 0.1524)
				(type default)
			)
			(layer "F.SilkS")
		)
		(fp_line
			(start -0.7874 -0.4064)
			(end 0.7874 -0.4064)
			(stroke
				(width 0.1524)
				(type default)
			)
			(layer "F.SilkS")
		)
		(fp_line
			(start 0.67945 0.3048)
			(end 0.120396 0.3048)
			(stroke
				(width 0.1)
				(type default)
			)
			(layer "F.Fab")
		)
		(fp_line
			(start 0.67945 -0.3048)
			(end 0.67945 0.3048)
			(stroke
				(width 0.1)
				(type default)
			)
			(layer "F.Fab")
		)
		(fp_line
			(start 0.12065 -0.2794)
			(end 0.12065 -0.3048)
			(stroke
				(width 0.1)
				(type default)
			)
			(layer "F.Fab")
		)
		(fp_line
			(start 0.12065 -0.3048)
			(end 0.67945 -0.3048)
			(stroke
				(width 0.1)
				(type default)
			)
			(layer "F.Fab")
		)
		(fp_line
			(start 0.120396 0.3048)
			(end 0.120396 0.2794)
			(stroke
				(width 0.1)
				(type default)
			)
			(layer "F.Fab")
		)
		(fp_line
			(start 0.120396 0.2794)
			(end -0.12065 0.2794)
			(stroke
				(width 0.1)
				(type default)
			)
			(layer "F.Fab")
		)
		(fp_line
			(start -0.12065 0.3048)
			(end -0.67945 0.3048)
			(stroke
				(width 0.1)
				(type default)
			)
			(layer "F.Fab")
		)
		(fp_line
			(start -0.12065 0.2794)
			(end -0.12065 0.3048)
			(stroke
				(width 0.1)
				(type default)
			)
			(layer "F.Fab")
		)
		(fp_line
			(start -0.12065 -0.2794)
			(end 0.12065 -0.2794)
			(stroke
				(width 0.1)
				(type default)
			)
			(layer "F.Fab")
		)
		(fp_line
			(start -0.12065 -0.305054)
			(end -0.12065 -0.2794)
			(stroke
				(width 0.1)
				(type default)
			)
			(layer "F.Fab")
		)
		(fp_line
			(start -0.67945 0.3048)
			(end -0.67945 -0.305054)
			(stroke
				(width 0.1)
				(type default)
			)
			(layer "F.Fab")
		)
		(fp_line
			(start -0.67945 -0.305054)
			(end -0.12065 -0.305054)
			(stroke
				(width 0.1)
				(type default)
			)
			(layer "F.Fab")
		)
		(pad "1" smd circle
			(at -0.40005 0 180)
			(size 0 0)
			(layers "F.Cu" "F.Mask" "F.Paste")
			(net "HSC_IMON")
		)
		(pad "2" smd circle
			(at 0.40005 0 180)
			(size 0 0)
			(layers "F.Cu" "F.Mask" "F.Paste")
			(net "AGND_HSC")
		)
	)
	(footprint ""
		(layer "F.Cu")
		(at 416.097974 -175.88865 180)
		(property "Reference" "PC190_P0_2"
			(at 0 0 180)
			(layer "F.SilkS")
			(hide yes)
			(effects
				(font
					(size 1.27 1.27)
				)
			)
		)
		(property "Value" ""
			(at 0 0 180)
			(layer "F.Fab")
			(effects
				(font
					(size 1.27 1.27)
				)
			)
		)
		(duplicate_pad_numbers_are_jumpers no)
		(fp_line
			(start 0.7874 0.4064)
			(end -0.7874 0.4064)
			(stroke
				(width 0.1524)
				(type default)
			)
			(layer "F.SilkS")
		)
		(fp_line
			(start 0.7874 -0.4064)
			(end 0.7874 0.4064)
			(stroke
				(width 0.1524)
				(type default)
			)
			(layer "F.SilkS")
		)
		(fp_line
			(start -0.7874 0.4064)
			(end -0.7874 -0.4064)
			(stroke
				(width 0.1524)
				(type default)
			)
			(layer "F.SilkS")
		)
		(fp_line
			(start -0.7874 -0.4064)
			(end 0.7874 -0.4064)
			(stroke
				(width 0.1524)
				(type default)
			)
			(layer "F.SilkS")
		)
		(fp_line
			(start 0.67945 0.3048)
			(end 0.120396 0.3048)
			(stroke
				(width 0.1)
				(type default)
			)
			(layer "F.Fab")
		)
		(fp_line
			(start 0.67945 -0.3048)
			(end 0.67945 0.3048)
			(stroke
				(width 0.1)
				(type default)
			)
			(layer "F.Fab")
		)
		(fp_line
			(start 0.12065 -0.2794)
			(end 0.12065 -0.3048)
			(stroke
				(width 0.1)
				(type default)
			)
			(layer "F.Fab")
		)
		(fp_line
			(start 0.12065 -0.3048)
			(end 0.67945 -0.3048)
			(stroke
				(width 0.1)
				(type default)
			)
			(layer "F.Fab")
		)
		(fp_line
			(start 0.120396 0.3048)
			(end 0.120396 0.2794)
			(stroke
				(width 0.1)
				(type default)
			)
			(layer "F.Fab")
		)
		(fp_line
			(start 0.120396 0.2794)
			(end -0.12065 0.2794)
			(stroke
				(width 0.1)
				(type default)
			)
			(layer "F.Fab")
		)
		(fp_line
			(start -0.12065 0.3048)
			(end -0.67945 0.3048)
			(stroke
				(width 0.1)
				(type default)
			)
			(layer "F.Fab")
		)
		(fp_line
			(start -0.12065 0.2794)
			(end -0.12065 0.3048)
			(stroke
				(width 0.1)
				(type default)
			)
			(layer "F.Fab")
		)
		(fp_line
			(start -0.12065 -0.2794)
			(end 0.12065 -0.2794)
			(stroke
				(width 0.1)
				(type default)
			)
			(layer "F.Fab")
		)
		(fp_line
			(start -0.12065 -0.305054)
			(end -0.12065 -0.2794)
			(stroke
				(width 0.1)
				(type default)
			)
			(layer "F.Fab")
		)
		(fp_line
			(start -0.67945 0.3048)
			(end -0.67945 -0.305054)
			(stroke
				(width 0.1)
				(type default)
			)
			(layer "F.Fab")
		)
		(fp_line
			(start -0.67945 -0.305054)
			(end -0.12065 -0.305054)
			(stroke
				(width 0.1)
				(type default)
			)
			(layer "F.Fab")
		)
		(pad "1" smd circle
			(at -0.40005 0 180)
			(size 0 0)
			(layers "F.Cu" "F.Mask" "F.Paste")
			(net "SW_P12V_PVCCINFAON_CPU0_FLT")
		)
		(pad "2" smd circle
			(at 0.40005 0 180)
			(size 0 0)
			(layers "F.Cu" "F.Mask" "F.Paste")
			(net "GND")
		)
	)
)
